FILE_TYPE = MULTI_PHYS_TABLE;
PART 'CONN4_D42317002'
{===========================================================================================================================================================================}
:PACK_TYPE|MATERIAL  |PART_NUMBER      = EnvComp |PART_NUMBER   |JEDEC_TYPE         |CLASS  |DESCRIPTION                         |HEIGHT      |COMPONENT_TYPE  |LEAD_LENGTH | SPEED_URL | Status |RPL| AML | Bus_Unit | Days ;
{===========================================================================================================================================================================}
'THMT'    | 'CONN'   | 'D42317-002'(!) = 'YES;YES;CNC;CNC;ok;VLD' | 'D42317-002' | 'CONN4_D42317002' | 'IO'  | 'CONN,HDR,1X4,PLG,VT,2MM,093ST,KP' | '0.244 IN' | 'THMT'         | '0.126' | 'http://speed.intel.com:8081/speed/module/pdm/item/pdm_item_detail_direct.asp?item_cde=D42317-002&item_rev=01&url_param=unused' | 'Conditional' | 'NO' | '2' | 'SMO_BOARDS' | '???' 
'THMT'    | 'EMPTY'  | 'D42317-002'(!) = 'YES;YES;CNC;CNC;ok;VLD' | 'D42317-002' | 'CONN4_D42317002' | 'IO'  | 'CONN,HDR,1X4,PLG,VT,2MM,093ST,KP' | '0.244 IN' | 'THMT'         | '0.126' | 'http://speed.intel.com:8081/speed/module/pdm/item/pdm_item_detail_direct.asp?item_cde=D42317-002&item_rev=01&url_param=unused' | 'Conditional' | 'NO' | '2' | 'SMO_BOARDS' | '???' 
'PIP'     | 'CONN'   | 'D42317-002'(!) = ''                       | 'D42317-002' | 'CONN4_D42317002_PIP' | 'IO'  | 'CONN,HDR,1X4,PLG,VT,2MM,093ST,KP' | '0.244 IN' | 'THMT'         | '0.126' | 'http://speed.intel.com:8081/speed/module/pdm/item/pdm_item_detail_direct.asp?item_cde=D42317-002&item_rev=01&url_param=unused' | '' | '' | '' | '' | '' 
'PIP'     | 'EMPTY'  | 'D42317-002'(!) = ''                       | 'D42317-002' | 'CONN4_D42317002_PIP' | 'IO'  | 'CONN,HDR,1X4,PLG,VT,2MM,093ST,KP' | '0.244 IN' | 'THMT'         | '0.126' | 'http://speed.intel.com:8081/speed/module/pdm/item/pdm_item_detail_direct.asp?item_cde=D42317-002&item_rev=01&url_param=unused' | '' | '' | '' | '' | '' 
END_PART
END.
